FILE_TYPE = CONNECTIVITY;
{Allegro Design Entry HDL 17.2-2016 S081 (4005846) 1/11/2022}
"PAGE_NUMBER" = 103;
0"NC";
1"P3V3_AUX\g";
2"P12V_S3_AUX_CPU1_NVDIMM\g";
3"P12V_S3_AUX_CPU1_NVDIMM\g";
4"P3V3_AUX\g";
5"GND\g";
6"GND\g";
7"GND\g";
8"GND\g";
9"GND\g";
10"M_C_CPU1_SA_DQ<31:0>";
11"M_C_CPU1_SA_CB<7:0>";
12"M_C_CPU1_SB_CB<7:0>";
13"M_C_CPU1_SA_CA<6:0>";
14"M_C_CPU1_SB_CA<6:0>";
15"M_C_CPU1_SB_DQ<31:0>";
16"M_C_CPU1_SB_DQS_DP<9:0>";
17"M_C_CPU1_SA_DQS_DP<9:0>";
18"M_C_CPU1_SB_DQS_DN<9:0>";
19"M_C_CPU1_SA_DQS_DN<9:0>";
20"M_C_CPU1_SB_DQ<4>";
21"M_C_CPU1_ALERT_N";
22"I3C_SPD_DDRABCD_CPU1_LVC1_SDA";
23"PD_CHC_CPU1_DIMM2_SAA";
24"RST_M_CD_CPU1_FPGA_N";
25"M_C_CPU1_SB_CB<0>";
26"I3C_SPD_DDRABCD_CPU1_LVC1_SCL_R6";
27"I3C_SPD_DDRABCD_CPU1_LVC1_SCL";
28"PWRGD_CHC_CPU1_DIMM2";
29"TP_CHC_CPU1_DIMM2_FRU_6";
30"M_C_CPU1_SB_CB<4>";
31"M_C_CPU1_SB_CS_N<2>";
32"M_C_CPU1_SB_CS_N<3>";
33"M_C_CPU1_SA_CS_N<2>";
34"M_C_CPU1_SB_DQS_DP<5>";
35"M_C_CPU1_SB_DQS_DN<5>";
36"M_C_CPU1_SA_DQS_DN<9>";
37"M_C_CPU1_SA_DQS_DN<8>";
38"M_C_CPU1_SA_DQS_DN<7>";
39"M_C_CPU1_SA_DQS_DN<6>";
40"M_C_CPU1_SA_DQS_DN<4>";
41"M_C_CPU1_SA_DQS_DN<5>";
42"M_C_CPU1_SA_DQS_DN<3>";
43"M_C_CPU1_SA_DQS_DN<2>";
44"M_C_CPU1_SA_DQS_DN<0>";
45"M_C_CPU1_SA_DQS_DN<1>";
46"M_C_CPU1_SB_DQS_DN<8>";
47"M_C_CPU1_SB_DQS_DN<9>";
48"M_C_CPU1_SB_DQS_DN<7>";
49"M_C_CPU1_SB_DQS_DN<6>";
50"M_C_CPU1_SB_DQS_DN<3>";
51"M_C_CPU1_SB_DQS_DN<4>";
52"M_C_CPU1_SB_DQS_DN<2>";
53"M_C_CPU1_SB_DQS_DN<1>";
54"M_C_CPU1_SB_DQS_DN<0>";
55"M_C_CPU1_SA_DQS_DP<9>";
56"M_C_CPU1_SA_DQS_DP<8>";
57"M_C_CPU1_SA_DQS_DP<7>";
58"M_C_CPU1_SA_DQS_DP<6>";
59"M_C_CPU1_SA_DQS_DP<5>";
60"M_C_CPU1_SA_DQS_DP<4>";
61"M_C_CPU1_SA_DQS_DP<3>";
62"M_C_CPU1_SA_DQS_DP<2>";
63"M_C_CPU1_SA_DQS_DP<1>";
64"M_C_CPU1_SA_DQS_DP<0>";
65"M_C_CPU1_SB_DQS_DP<9>";
66"M_C_CPU1_SB_DQS_DP<8>";
67"M_C_CPU1_SB_DQS_DP<7>";
68"M_C_CPU1_SB_DQS_DP<6>";
69"M_C_CPU1_SB_DQS_DP<4>";
70"M_C_CPU1_SB_DQS_DP<3>";
71"M_C_CPU1_SB_DQS_DP<2>";
72"M_C_CPU1_SB_DQS_DP<1>";
73"M_C_CPU1_SB_DQS_DP<0>";
74"M_C_CPU1_SB_DQ<10>";
75"M_C_CPU1_SB_DQ<18>";
76"M_C_CPU1_SA_DQ<28>";
77"M_C_CPU1_SA_CA<2>";
78"M_C_CPU1_CLK_DP<1>";
79"M_C_CPU1_CLK_DN<1>";
80"M_C_CPU1_SB_DQ<31>";
81"M_C_CPU1_SB_DQ<30>";
82"M_C_CPU1_SB_DQ<24>";
83"TP_CHC_CPU1_DIMM2_FRU_0";
84"TP_CHC_CPU1_DIMM2_FRU_1";
85"TP_CHC_CPU1_DIMM2_FRU_2";
86"TP_CHC_CPU1_DIMM2_FRU_3";
87"TP_CHC_CPU1_DIMM2_FRU_4";
88"TP_CHC_CPU1_DIMM2_FRU_5";
89"M_C_CPU1_SB_PAR";
90"M_C_CPU1_SA_PAR";
91"M_C_CPU1_SB_RSP<1>";
92"M_C_CPU1_SA_RSP<1>";
93"M_C_CPU1_SB_DQ<0>";
94"M_C_CPU1_SB_DQ<1>";
95"M_C_CPU1_SB_DQ<2>";
96"M_C_CPU1_SB_DQ<3>";
97"M_C_CPU1_SB_DQ<5>";
98"M_C_CPU1_SB_DQ<6>";
99"M_C_CPU1_SB_DQ<7>";
100"M_C_CPU1_SB_DQ<8>";
101"M_C_CPU1_SB_DQ<9>";
102"M_C_CPU1_SB_DQ<11>";
103"M_C_CPU1_SB_DQ<12>";
104"M_C_CPU1_SB_DQ<13>";
105"M_C_CPU1_SB_DQ<14>";
106"M_C_CPU1_SB_DQ<15>";
107"M_C_CPU1_SB_DQ<16>";
108"M_C_CPU1_SB_DQ<17>";
109"M_C_CPU1_SB_DQ<19>";
110"M_C_CPU1_SB_DQ<20>";
111"M_C_CPU1_SB_DQ<21>";
112"M_C_CPU1_SB_DQ<22>";
113"M_C_CPU1_SB_DQ<23>";
114"M_C_CPU1_SB_DQ<25>";
115"M_C_CPU1_SB_DQ<26>";
116"M_C_CPU1_SB_DQ<27>";
117"M_C_CPU1_SB_DQ<28>";
118"M_C_CPU1_SB_DQ<29>";
119"M_C_CPU1_SA_DQ<0>";
120"M_C_CPU1_SA_DQ<1>";
121"M_C_CPU1_SA_DQ<2>";
122"M_C_CPU1_SA_DQ<3>";
123"M_C_CPU1_SA_DQ<4>";
124"M_C_CPU1_SA_DQ<5>";
125"M_C_CPU1_SA_DQ<6>";
126"M_C_CPU1_SA_DQ<7>";
127"M_C_CPU1_SA_DQ<8>";
128"M_C_CPU1_SA_DQ<9>";
129"M_C_CPU1_SA_DQ<10>";
130"M_C_CPU1_SA_DQ<11>";
131"M_C_CPU1_SA_DQ<12>";
132"M_C_CPU1_SA_DQ<13>";
133"M_C_CPU1_SA_DQ<14>";
134"M_C_CPU1_SA_DQ<15>";
135"M_C_CPU1_SA_DQ<16>";
136"M_C_CPU1_SA_DQ<17>";
137"M_C_CPU1_SA_DQ<18>";
138"M_C_CPU1_SA_DQ<19>";
139"M_C_CPU1_SA_DQ<20>";
140"M_C_CPU1_SA_DQ<21>";
141"M_C_CPU1_SA_DQ<22>";
142"M_C_CPU1_SA_DQ<23>";
143"M_C_CPU1_SA_DQ<24>";
144"M_C_CPU1_SA_DQ<25>";
145"M_C_CPU1_SA_DQ<26>";
146"M_C_CPU1_SA_DQ<27>";
147"M_C_CPU1_SA_DQ<29>";
148"M_C_CPU1_SA_DQ<30>";
149"M_C_CPU1_SA_CS_N<3>";
150"M_C_CPU1_SB_CB<1>";
151"M_C_CPU1_SB_CB<2>";
152"M_C_CPU1_SB_CB<3>";
153"M_C_CPU1_SB_CB<5>";
154"M_C_CPU1_SB_CB<6>";
155"M_C_CPU1_SA_CB<0>";
156"M_C_CPU1_SA_CB<2>";
157"M_C_CPU1_SA_CB<3>";
158"M_C_CPU1_SA_CB<5>";
159"M_C_CPU1_SA_CB<6>";
160"M_C_CPU1_SB_CA<6>";
161"M_C_CPU1_SA_CA<6>";
162"M_C_CPU1_SB_CA<5>";
163"M_C_CPU1_SA_CA<5>";
164"M_C_CPU1_SB_CA<4>";
165"M_C_CPU1_SA_CA<4>";
166"M_C_CPU1_SB_CA<3>";
167"M_C_CPU1_SA_CA<3>";
168"M_C_CPU1_SB_CA<2>";
169"M_C_CPU1_SB_CA<1>";
170"M_C_CPU1_SA_CA<1>";
171"M_C_CPU1_SB_CA<0>";
172"M_C_CPU1_SA_CA<0>";
173"M_C_CPU1_SB_CB<7>";
174"M_C_CPU1_SA_CB<1>";
175"M_C_CPU1_SA_CB<4>";
176"M_C_CPU1_SA_CB<7>";
177"M_C_CPU1_SA_DQ<31>";
178"PD_CHC_CPU1_DIMM2_SAA";
%"UNIVERSAL_GND"
"1","(-2675,-475)","0","logical_power","I1";
;
HDL_POWER"GND"
CDS_LIB"logical_power";
"A"5;
%"TAP"
"1","(-1250,3100)","0","standard","I100";
;
CDS_LIB"standard"
BODY_TYPE"PLUMBING"
HDL_TAP"TRUE";
"B \NAC \NWC"10;
"S \NAC"
BN"15"134;
%"TAP"
"1","(-1250,3200)","0","standard","I101";
;
CDS_LIB"standard"
BODY_TYPE"PLUMBING"
HDL_TAP"TRUE";
"B \NAC \NWC"10;
"S \NAC"
BN"17"136;
%"TAP"
"1","(-1250,3250)","0","standard","I102";
;
CDS_LIB"standard"
BODY_TYPE"PLUMBING"
HDL_TAP"TRUE";
"B \NAC \NWC"10;
"S \NAC"
BN"18"137;
%"TAP"
"1","(-1250,3300)","0","standard","I103";
;
CDS_LIB"standard"
BODY_TYPE"PLUMBING"
HDL_TAP"TRUE";
"B \NAC \NWC"10;
"S \NAC"
BN"19"138;
%"TAP"
"1","(-1250,3350)","0","standard","I104";
;
CDS_LIB"standard"
BODY_TYPE"PLUMBING"
HDL_TAP"TRUE";
"B \NAC \NWC"10;
"S \NAC"
BN"20"139;
%"TAP"
"1","(-1250,3400)","0","standard","I105";
;
CDS_LIB"standard"
BODY_TYPE"PLUMBING"
HDL_TAP"TRUE";
"B \NAC \NWC"10;
"S \NAC"
BN"21"140;
%"TAP"
"1","(-1250,3450)","0","standard","I106";
;
CDS_LIB"standard"
BODY_TYPE"PLUMBING"
HDL_TAP"TRUE";
"B \NAC \NWC"10;
"S \NAC"
BN"22"141;
%"TAP"
"1","(-1250,3500)","0","standard","I107";
;
CDS_LIB"standard"
BODY_TYPE"PLUMBING"
HDL_TAP"TRUE";
"B \NAC \NWC"10;
"S \NAC"
BN"23"142;
%"TAP"
"1","(-1250,3600)","0","standard","I108";
;
CDS_LIB"standard"
BODY_TYPE"PLUMBING"
HDL_TAP"TRUE";
"B \NAC \NWC"10;
"S \NAC"
BN"25"144;
%"TAP"
"1","(-1250,3550)","0","standard","I109";
;
CDS_LIB"standard"
BODY_TYPE"PLUMBING"
HDL_TAP"TRUE";
"B \NAC \NWC"10;
"S \NAC"
BN"24"143;
%"TAP"
"1","(-1250,3650)","0","standard","I110";
;
CDS_LIB"standard"
BODY_TYPE"PLUMBING"
HDL_TAP"TRUE";
"B \NAC \NWC"10;
"S \NAC"
BN"26"145;
%"TAP"
"1","(-1250,3700)","0","standard","I111";
;
CDS_LIB"standard"
BODY_TYPE"PLUMBING"
HDL_TAP"TRUE";
"B \NAC \NWC"10;
"S \NAC"
BN"27"146;
%"TAP"
"1","(-1250,3750)","0","standard","I112";
;
CDS_LIB"standard"
BODY_TYPE"PLUMBING"
HDL_TAP"TRUE";
"B \NAC \NWC"10;
"S \NAC"
BN"28"76;
%"TAP"
"1","(-2900,3800)","2","standard","I114";
;
CDS_LIB"standard"
BODY_TYPE"PLUMBING"
HDL_TAP"TRUE";
"B \NAC \NWC"13;
"S \NAC"
BN"4"165;
%"TAP"
"1","(-2900,3850)","2","standard","I115";
;
CDS_LIB"standard"
BODY_TYPE"PLUMBING"
HDL_TAP"TRUE";
"B \NAC \NWC"13;
"S \NAC"
BN"5"163;
%"TAP"
"1","(-2900,3900)","2","standard","I116";
;
CDS_LIB"standard"
BODY_TYPE"PLUMBING"
HDL_TAP"TRUE";
"B \NAC \NWC"13;
"S \NAC"
BN"6"161;
%"TAP"
"1","(-1250,3800)","0","standard","I117";
;
CDS_LIB"standard"
BODY_TYPE"PLUMBING"
HDL_TAP"TRUE";
"B \NAC \NWC"10;
"S \NAC"
BN"29"147;
%"TAP"
"1","(-1250,3850)","0","standard","I118";
;
CDS_LIB"standard"
BODY_TYPE"PLUMBING"
HDL_TAP"TRUE";
"B \NAC \NWC"10;
"S \NAC"
BN"30"148;
%"TAP"
"1","(-1250,3900)","0","standard","I119";
;
CDS_LIB"standard"
BODY_TYPE"PLUMBING"
HDL_TAP"TRUE";
"B \NAC \NWC"10;
"S \NAC"
BN"31"177;
%"VCC_CORE"
"1","(-3725,1775)","0","logical_power","I12";
;
HDL_POWER"P3V3_AUX"
CDS_LIB"logical_power";
"A"4;
%"UNIVERSAL_GND"
"1","(475,-350)","0","logical_power","I120";
;
HDL_POWER"GND"
CDS_LIB"logical_power";
"A"6;
%"UNIVERSAL_GND"
"1","(2100,-350)","0","logical_power","I121";
;
HDL_POWER"GND"
CDS_LIB"logical_power";
"A"7;
%"Q_CAP"
"1","(475,25)","0","pure_quanta","I122";
;
PART_NUMBER"CH5221MEB00"
VOLTAGE"6.3V"
VALUE"2.2UF"
TOLERANCE"20%"
MATERIAL"X6S"
PACK_TYPE"C0402"
$LOCATION"C65"
CDS_LIB"pure_quanta"
$LOCATION"C65"
CDS_LOCATION"C65"
$SEC"1"
CDS_SEC"1";
"B"
$PN"2"6;
"A"
$PN"1"1;
%"VCC_CORE"
"1","(475,350)","0","logical_power","I123";
;
HDL_POWER"P3V3_AUX"
CDS_LIB"logical_power";
"A"1;
%"Q_CAP"
"1","(1475,25)","0","pure_quanta","I126";
;
PART_NUMBER"CH6103KEA00"
TOLERANCE"10%"
PACK_TYPE"C0805"
VOLTAGE"16V"
VALUE"10UF"
MATERIAL"X6S"
$LOCATION"C66"
CDS_LIB"pure_quanta"
$LOCATION"C66"
CDS_LOCATION"C66"
$SEC"1"
CDS_SEC"1";
"B"
$PN"2"7;
"A"
$PN"1"2;
%"VCC_CORE"
"1","(1475,350)","0","logical_power","I127";
;
HDL_POWER"P12V_S3_AUX_CPU1_NVDIMM"
CDS_LIB"logical_power";
"A"2;
%"Q_CAP"
"1","(2100,25)","0","pure_quanta","I128";
;
PART_NUMBER"CH6103KEA00"
TOLERANCE"10%"
PACK_TYPE"C0805"
VOLTAGE"16V"
VALUE"10UF"
MATERIAL"X6S"
$LOCATION"C67"
CDS_LIB"pure_quanta"
$LOCATION"C67"
CDS_LOCATION"C67"
$SEC"1"
CDS_SEC"1";
"B"
$PN"2"7;
"A"
$PN"1"2;
%"UNIVERSAL_GND"
"1","(3175,200)","0","logical_power","I129";
;
HDL_POWER"GND"
CDS_LIB"logical_power";
"A"8;
%"TAP"
"1","(-2900,1700)","2","standard","I13";
;
CDS_LIB"standard"
BODY_TYPE"PLUMBING"
HDL_TAP"TRUE";
"B \NAC \NWC"12;
"S \NAC"
BN"0"25;
%"TAP"
"1","(1500,1950)","0","standard","I130";
;
CDS_LIB"standard"
BODY_TYPE"PLUMBING"
HDL_TAP"TRUE";
"B \NAC \NWC"16;
"S \NAC"
BN"0"73;
%"TAP"
"1","(1500,2050)","0","standard","I131";
;
CDS_LIB"standard"
BODY_TYPE"PLUMBING"
HDL_TAP"TRUE";
"B \NAC \NWC"16;
"S \NAC"
BN"1"72;
%"TAP"
"1","(1500,2150)","0","standard","I132";
;
CDS_LIB"standard"
BODY_TYPE"PLUMBING"
HDL_TAP"TRUE";
"B \NAC \NWC"16;
"S \NAC"
BN"2"71;
%"TAP"
"1","(1500,2250)","0","standard","I133";
;
CDS_LIB"standard"
BODY_TYPE"PLUMBING"
HDL_TAP"TRUE";
"B \NAC \NWC"16;
"S \NAC"
BN"3"70;
%"TAP"
"1","(1675,2000)","0","standard","I134";
;
CDS_LIB"standard"
BODY_TYPE"PLUMBING"
HDL_TAP"TRUE";
"B \NAC \NWC"18;
"S \NAC"
BN"1"53;
%"TAP"
"1","(1675,1900)","0","standard","I135";
;
CDS_LIB"standard"
BODY_TYPE"PLUMBING"
HDL_TAP"TRUE";
"B \NAC \NWC"18;
"S \NAC"
BN"0"54;
%"TAP"
"1","(1675,2100)","0","standard","I136";
;
CDS_LIB"standard"
BODY_TYPE"PLUMBING"
HDL_TAP"TRUE";
"B \NAC \NWC"18;
"S \NAC"
BN"2"52;
%"TAP"
"1","(1675,2200)","0","standard","I137";
;
CDS_LIB"standard"
BODY_TYPE"PLUMBING"
HDL_TAP"TRUE";
"B \NAC \NWC"18;
"S \NAC"
BN"3"50;
%"TAP"
"1","(1500,2350)","0","standard","I138";
;
CDS_LIB"standard"
BODY_TYPE"PLUMBING"
HDL_TAP"TRUE";
"B \NAC \NWC"16;
"S \NAC"
BN"4"69;
%"TAP"
"1","(1500,2450)","0","standard","I139";
;
CDS_LIB"standard"
BODY_TYPE"PLUMBING"
HDL_TAP"TRUE";
"B \NAC \NWC"16;
"S \NAC"
BN"5"34;
%"TAP"
"1","(1500,2550)","0","standard","I140";
;
CDS_LIB"standard"
BODY_TYPE"PLUMBING"
HDL_TAP"TRUE";
"B \NAC \NWC"16;
"S \NAC"
BN"6"68;
%"TAP"
"1","(1500,2650)","0","standard","I141";
;
CDS_LIB"standard"
BODY_TYPE"PLUMBING"
HDL_TAP"TRUE";
"B \NAC \NWC"16;
"S \NAC"
BN"7"67;
%"TAP"
"1","(1500,2750)","0","standard","I142";
;
CDS_LIB"standard"
BODY_TYPE"PLUMBING"
HDL_TAP"TRUE";
"B \NAC \NWC"16;
"S \NAC"
BN"8"66;
%"TAP"
"1","(1675,2300)","0","standard","I143";
;
CDS_LIB"standard"
BODY_TYPE"PLUMBING"
HDL_TAP"TRUE";
"B \NAC \NWC"18;
"S \NAC"
BN"4"51;
%"TAP"
"1","(1675,2500)","0","standard","I144";
;
CDS_LIB"standard"
BODY_TYPE"PLUMBING"
HDL_TAP"TRUE";
"B \NAC \NWC"18;
"S \NAC"
BN"6"49;
%"TAP"
"1","(1675,2400)","0","standard","I145";
;
CDS_LIB"standard"
BODY_TYPE"PLUMBING"
HDL_TAP"TRUE";
"B \NAC \NWC"18;
"S \NAC"
BN"5"35;
%"TAP"
"1","(1675,2600)","0","standard","I146";
;
CDS_LIB"standard"
BODY_TYPE"PLUMBING"
HDL_TAP"TRUE";
"B \NAC \NWC"18;
"S \NAC"
BN"7"48;
%"TAP"
"1","(1675,2700)","0","standard","I147";
;
CDS_LIB"standard"
BODY_TYPE"PLUMBING"
HDL_TAP"TRUE";
"B \NAC \NWC"18;
"S \NAC"
BN"8"46;
%"TAP"
"1","(1500,2850)","0","standard","I148";
;
CDS_LIB"standard"
BODY_TYPE"PLUMBING"
HDL_TAP"TRUE";
"B \NAC \NWC"16;
"S \NAC"
BN"9"65;
%"TAP"
"1","(1500,3000)","0","standard","I149";
;
CDS_LIB"standard"
BODY_TYPE"PLUMBING"
HDL_TAP"TRUE";
"B \NAC \NWC"17;
"S \NAC"
BN"0"64;
%"TAP"
"1","(1500,3100)","0","standard","I150";
;
CDS_LIB"standard"
BODY_TYPE"PLUMBING"
HDL_TAP"TRUE";
"B \NAC \NWC"17;
"S \NAC"
BN"1"63;
%"TAP"
"1","(1500,3200)","0","standard","I151";
;
CDS_LIB"standard"
BODY_TYPE"PLUMBING"
HDL_TAP"TRUE";
"B \NAC \NWC"17;
"S \NAC"
BN"2"62;
%"TAP"
"1","(1675,2800)","0","standard","I152";
;
CDS_LIB"standard"
BODY_TYPE"PLUMBING"
HDL_TAP"TRUE";
"B \NAC \NWC"18;
"S \NAC"
BN"9"47;
%"TAP"
"1","(1675,2950)","0","standard","I153";
;
CDS_LIB"standard"
BODY_TYPE"PLUMBING"
HDL_TAP"TRUE";
"B \NAC \NWC"19;
"S \NAC"
BN"0"44;
%"TAP"
"1","(1675,3150)","0","standard","I154";
;
CDS_LIB"standard"
BODY_TYPE"PLUMBING"
HDL_TAP"TRUE";
"B \NAC \NWC"19;
"S \NAC"
BN"2"43;
%"TAP"
"1","(1675,3050)","0","standard","I155";
;
CDS_LIB"standard"
BODY_TYPE"PLUMBING"
HDL_TAP"TRUE";
"B \NAC \NWC"19;
"S \NAC"
BN"1"45;
%"TAP"
"1","(1675,3250)","0","standard","I156";
;
CDS_LIB"standard"
BODY_TYPE"PLUMBING"
HDL_TAP"TRUE";
"B \NAC \NWC"19;
"S \NAC"
BN"3"42;
%"TAP"
"1","(1500,3300)","0","standard","I157";
;
CDS_LIB"standard"
BODY_TYPE"PLUMBING"
HDL_TAP"TRUE";
"B \NAC \NWC"17;
"S \NAC"
BN"3"61;
%"TAP"
"1","(1500,3400)","0","standard","I158";
;
CDS_LIB"standard"
BODY_TYPE"PLUMBING"
HDL_TAP"TRUE";
"B \NAC \NWC"17;
"S \NAC"
BN"4"60;
%"TAP"
"1","(1500,3500)","0","standard","I159";
;
CDS_LIB"standard"
BODY_TYPE"PLUMBING"
HDL_TAP"TRUE";
"B \NAC \NWC"17;
"S \NAC"
BN"5"59;
%"TAP"
"1","(1500,3600)","0","standard","I160";
;
CDS_LIB"standard"
BODY_TYPE"PLUMBING"
HDL_TAP"TRUE";
"B \NAC \NWC"17;
"S \NAC"
BN"6"58;
%"TAP"
"1","(1500,3700)","0","standard","I161";
;
CDS_LIB"standard"
BODY_TYPE"PLUMBING"
HDL_TAP"TRUE";
"B \NAC \NWC"17;
"S \NAC"
BN"7"57;
%"TAP"
"1","(1675,3350)","0","standard","I162";
;
CDS_LIB"standard"
BODY_TYPE"PLUMBING"
HDL_TAP"TRUE";
"B \NAC \NWC"19;
"S \NAC"
BN"4"40;
%"TAP"
"1","(1675,3450)","0","standard","I163";
;
CDS_LIB"standard"
BODY_TYPE"PLUMBING"
HDL_TAP"TRUE";
"B \NAC \NWC"19;
"S \NAC"
BN"5"41;
%"TAP"
"1","(1675,3650)","0","standard","I164";
;
CDS_LIB"standard"
BODY_TYPE"PLUMBING"
HDL_TAP"TRUE";
"B \NAC \NWC"19;
"S \NAC"
BN"7"38;
%"TAP"
"1","(1675,3550)","0","standard","I165";
;
CDS_LIB"standard"
BODY_TYPE"PLUMBING"
HDL_TAP"TRUE";
"B \NAC \NWC"19;
"S \NAC"
BN"6"39;
%"TAP"
"1","(1675,3750)","0","standard","I166";
;
CDS_LIB"standard"
BODY_TYPE"PLUMBING"
HDL_TAP"TRUE";
"B \NAC \NWC"19;
"S \NAC"
BN"8"37;
%"TAP"
"1","(1500,3900)","0","standard","I170";
;
CDS_LIB"standard"
BODY_TYPE"PLUMBING"
HDL_TAP"TRUE";
"B \NAC \NWC"17;
"S \NAC"
BN"9"55;
%"TAP"
"1","(1500,3800)","0","standard","I171";
;
CDS_LIB"standard"
BODY_TYPE"PLUMBING"
HDL_TAP"TRUE";
"B \NAC \NWC"17;
"S \NAC"
BN"8"56;
%"TAP"
"1","(1675,3850)","0","standard","I172";
;
CDS_LIB"standard"
BODY_TYPE"PLUMBING"
HDL_TAP"TRUE";
"B \NAC \NWC"19;
"S \NAC"
BN"9"36;
%"VCC_CORE"
"1","(3175,4450)","0","logical_power","I175";
;
HDL_POWER"P12V_S3_AUX_CPU1_NVDIMM"
CDS_LIB"logical_power";
"A"3;
%"SCONN288_ADR50017P087CC"
"3","(4025,2275)","0","pure_quanta","I176";
;
PART_NUMBER"DFHST8FS460"
PART_TYPE"SMLF"
VALUE"SCONN288_ADR50017-P087CC"
MATERIAL"IO"
$LOCATION"J22"
NEEDS_NO_SIZE"TRUE"
CDS_LMAN_SYM_OUTLINE"-450,1775,450,-1775"
CDS_LIB"pure_quanta"
CDS_LOCATION"J22"
$SEC"3"
CDS_SEC"3";
"G3"
$PN"G3"9;
"G2"
$PN"G2"9;
"G1"
$PN"G1"9;
"VSS62"
$PN"141"9;
"VSS61"
$PN"139"9;
"VSS60"
$PN"136"9;
"VSS58"
$PN"132"9;
"VSS104"
$PN"240"8;
"VSS102"
$PN"235"8;
"VSS100"
$PN"230"8;
"VIN_BULK2"
$PN"146"3;
"VIN_BULK1"
$PN"145"3;
"VIN_BULK0"
$PN"1"3;
"VSS126"
$PN"288"8;
"VSS125"
$PN"286"8;
"VSS124"
$PN"284"8;
"VSS123"
$PN"281"8;
"VSS122"
$PN"279"8;
"VSS121"
$PN"277"8;
"VSS120"
$PN"275"8;
"VSS119"
$PN"273"8;
"VSS118"
$PN"270"8;
"VSS117"
$PN"268"8;
"VSS116"
$PN"266"8;
"VSS115"
$PN"264"8;
"VSS114"
$PN"262"8;
"VSS113"
$PN"259"8;
"VSS112"
$PN"257"8;
"VSS111"
$PN"255"8;
"VSS110"
$PN"253"8;
"VSS109"
$PN"251"8;
"VSS108"
$PN"248"8;
"VSS107"
$PN"246"8;
"VSS106"
$PN"244"8;
"VSS105"
$PN"242"8;
"VSS103"
$PN"237"8;
"VSS101"
$PN"233"8;
"VSS99"
$PN"228"8;
"VSS98"
$PN"226"8;
"VSS97"
$PN"224"8;
"VSS96"
$PN"222"8;
"VSS95"
$PN"219"8;
"VSS94"
$PN"216"8;
"VSS93"
$PN"214"8;
"VSS92"
$PN"212"8;
"VSS91"
$PN"210"8;
"VSS90"
$PN"208"8;
"VSS89"
$PN"206"8;
"VSS88"
$PN"204"8;
"VSS87"
$PN"202"8;
"VSS86"
$PN"199"8;
"VSS85"
$PN"197"8;
"VSS84"
$PN"195"8;
"VSS83"
$PN"193"8;
"VSS82"
$PN"191"8;
"VSS81"
$PN"188"8;
"VSS80"
$PN"186"8;
"VSS79"
$PN"184"8;
"VSS78"
$PN"182"8;
"VSS77"
$PN"180"8;
"VSS76"
$PN"177"8;
"VSS75"
$PN"175"8;
"VSS74"
$PN"173"8;
"VSS73"
$PN"171"8;
"VSS72"
$PN"169"8;
"VSS71"
$PN"166"8;
"VSS70"
$PN"164"8;
"VSS69"
$PN"162"8;
"VSS68"
$PN"160"8;
"VSS67"
$PN"158"8;
"VSS66"
$PN"155"8;
"VSS65"
$PN"153"8;
"VSS64"
$PN"151"8;
"VSS63"
$PN"143"9;
"VSS59"
$PN"134"9;
"VSS57"
$PN"130"9;
"VSS56"
$PN"128"9;
"VSS55"
$PN"125"9;
"VSS54"
$PN"123"9;
"VSS53"
$PN"121"9;
"VSS52"
$PN"119"9;
"VSS51"
$PN"117"9;
"VSS50"
$PN"114"9;
"VSS49"
$PN"112"9;
"VSS48"
$PN"110"9;
"VSS47"
$PN"108"9;
"VSS46"
$PN"106"9;
"VSS45"
$PN"103"9;
"VSS44"
$PN"101"9;
"VSS43"
$PN"99"9;
"VSS42"
$PN"97"9;
"VSS41"
$PN"95"9;
"VSS40"
$PN"92"9;
"VSS39"
$PN"90"9;
"VSS38"
$PN"88"9;
"VSS37"
$PN"85"9;
"VSS36"
$PN"83"9;
"VSS35"
$PN"81"9;
"VSS34"
$PN"79"9;
"VSS33"
$PN"77"9;
"VSS32"
$PN"75"9;
"VSS31"
$PN"73"9;
"VSS30"
$PN"71"9;
"VSS29"
$PN"69"9;
"VSS28"
$PN"67"9;
"VSS27"
$PN"65"9;
"VSS26"
$PN"63"9;
"VSS25"
$PN"61"9;
"VSS24"
$PN"59"9;
"VSS23"
$PN"57"9;
"VSS22"
$PN"54"9;
"VSS21"
$PN"52"9;
"VSS20"
$PN"50"9;
"VSS19"
$PN"48"9;
"VSS18"
$PN"46"9;
"VSS17"
$PN"43"9;
"VSS16"
$PN"41"9;
"VSS15"
$PN"39"9;
"VSS14"
$PN"37"9;
"VSS13"
$PN"35"9;
"VSS12"
$PN"32"9;
"VSS11"
$PN"30"9;
"VSS10"
$PN"28"9;
"VSS9"
$PN"26"9;
"VSS8"
$PN"24"9;
"VSS7"
$PN"21"9;
"VSS6"
$PN"19"9;
"VSS5"
$PN"17"9;
"VSS4"
$PN"15"9;
"VSS3"
$PN"13"9;
"VSS2"
$PN"10"9;
"VSS1"
$PN"8"9;
"VSS0"
$PN"6"9;
%"UNIVERSAL_GND"
"1","(4875,200)","0","logical_power","I177";
;
HDL_POWER"GND"
CDS_LIB"logical_power";
"A"9;
%"SCONN288_ADR50017P087CC"
"2","(600,2900)","0","pure_quanta","I178";
;
PART_NUMBER"DFHST8FS460"
PART_TYPE"SMLF"
MATERIAL"IO"
VALUE"SCONN288_ADR50017-P087CC"
LOCATION"J22"
NEEDS_NO_SIZE"TRUE"
CDS_LMAN_SYM_OUTLINE"-600,1150,600,-1150"
CDS_LIB"pure_quanta"
$SEC"2"
CDS_SEC"2";
"DQS7_A_C||TDQS7_A_C \B"
$PN"178"38;
"DQS6_A_T||TDQS6_A_T"
$PN"168"58;
"DQS8_B_T||TDQS8_B_T"
$PN"283"66;
"DQS8_B_C||TDQS8_B_C \B"
$PN"282"46;
"DQS7_B_T||TDQS7_B_T"
$PN"272"67;
"DQS0_A_C \B"
$PN"12"44;
"DQS0_A_T"
$PN"11"64;
"DQS0_B_C \B"
$PN"105"54;
"DQS0_B_T"
$PN"104"73;
"DQS1_A_C \B"
$PN"23"45;
"DQS1_A_T"
$PN"22"63;
"DQS1_B_C \B"
$PN"116"53;
"DQS1_B_T"
$PN"115"72;
"DQS2_A_C \B"
$PN"34"43;
"DQS2_A_T"
$PN"33"62;
"DQS2_B_C \B"
$PN"127"52;
"DQS2_B_T"
$PN"126"71;
"DQS3_A_C \B"
$PN"45"42;
"DQS3_A_T"
$PN"44"61;
"DQS3_B_C \B"
$PN"138"50;
"DQS3_B_T"
$PN"137"70;
"DQS4_A_C \B"
$PN"56"40;
"DQS4_A_T"
$PN"55"60;
"DQS4_B_C \B"
$PN"238"51;
"DQS4_B_T"
$PN"239"69;
"DQS5_A_C||TDQS5_A_C||DQS5_A_T||TDQS5_A_T \B"
$PN"156"41;
"DQS5_A_T||TDQS5_A_T"
$PN"157"59;
"DQS5_B_C||TDQS5_B_C \B"
$PN"249"35;
"DQS5_B_T||TDQS5_B_T"
$PN"250"34;
"DQS6_A_C||TDQS6_A_C||DQS6_A_T||TDQS6_A_T \B"
$PN"167"39;
"DQS6_B_C||TDQS6_B_C \B"
$PN"260"49;
"DQS6_B_T||TDQS6_B_T"
$PN"261"68;
"DQS7_A_T||TDQS7_A_T"
$PN"179"57;
"DQS7_B_C||TDQS7_B_C \B"
$PN"271"48;
"DQS8_A_C||TDQS8_A_C \B"
$PN"189"37;
"DQS8_A_T||TDQS8_A_T"
$PN"190"56;
"DQS9_A_C||TDQS9_A_C \B"
$PN"200"36;
"DQS9_A_T||TDQS9_A_T"
$PN"201"55;
"DQS9_B_C||TDQS9_B_C \B"
$PN"94"47;
"DQS9_B_T||TDQS9_B_T||DBI4_B_N"
$PN"93"65;
%"Q_RES"
"1","(-3850,1200)","0","pure_quanta","I180";
;
PART_NUMBER"CS04992FB07"
VALUE"49.9"
MATERIAL"CHIP"
$LOCATION"R3896"
CDS_LIB"pure_quanta"
PACK_TYPE"0402LF"
TOLERANCE"1%"
WATTAGE"1/16W"
CDS_LOCATION"R3896"
$SEC"1"
CDS_SEC"1";
"B"
$PN"2"27;
"A"
$PN"1"26;
%"Q_RES"
"2","(-2675,-250)","0","pure_quanta","I2";
;
PART_NUMBER"CS38452FB05"
VALUE"84.5K"
PACK_TYPE"0402LF"
WATTAGE"1/16W"
TOLERANCE"1%"
MATERIAL"CHIP"
$LOCATION"R47"
CDS_LIB"pure_quanta"
$LOCATION"R47"
CDS_LOCATION"R47"
$SEC"1"
CDS_SEC"1";
"A"
$PN"1"178;
"B"
$PN"2"5;
%"TAP"
"1","(-2900,1750)","2","standard","I25";
;
CDS_LIB"standard"
BODY_TYPE"PLUMBING"
HDL_TAP"TRUE";
"B \NAC \NWC"12;
"S \NAC"
BN"1"150;
%"TAP"
"1","(-2900,1800)","2","standard","I26";
;
CDS_LIB"standard"
BODY_TYPE"PLUMBING"
HDL_TAP"TRUE";
"B \NAC \NWC"12;
"S \NAC"
BN"2"151;
%"TAP"
"1","(-2900,1850)","2","standard","I27";
;
CDS_LIB"standard"
BODY_TYPE"PLUMBING"
HDL_TAP"TRUE";
"B \NAC \NWC"12;
"S \NAC"
BN"3"152;
%"TAP"
"1","(-2900,1900)","2","standard","I28";
;
CDS_LIB"standard"
BODY_TYPE"PLUMBING"
HDL_TAP"TRUE";
"B \NAC \NWC"12;
"S \NAC"
BN"4"30;
%"TAP"
"1","(-2900,1950)","2","standard","I29";
;
CDS_LIB"standard"
BODY_TYPE"PLUMBING"
HDL_TAP"TRUE";
"B \NAC \NWC"12;
"S \NAC"
BN"5"153;
%"TAP"
"1","(-2900,2000)","2","standard","I30";
;
CDS_LIB"standard"
BODY_TYPE"PLUMBING"
HDL_TAP"TRUE";
"B \NAC \NWC"12;
"S \NAC"
BN"6"154;
%"TAP"
"1","(-2900,2050)","2","standard","I31";
;
CDS_LIB"standard"
BODY_TYPE"PLUMBING"
HDL_TAP"TRUE";
"B \NAC \NWC"12;
"S \NAC"
BN"7"173;
%"TAP"
"1","(-2900,2150)","2","standard","I32";
;
CDS_LIB"standard"
BODY_TYPE"PLUMBING"
HDL_TAP"TRUE";
"B \NAC \NWC"11;
"S \NAC"
BN"0"155;
%"TAP"
"1","(-2900,2200)","2","standard","I33";
;
CDS_LIB"standard"
BODY_TYPE"PLUMBING"
HDL_TAP"TRUE";
"B \NAC \NWC"11;
"S \NAC"
BN"1"174;
%"TAP"
"1","(-2900,2250)","2","standard","I34";
;
CDS_LIB"standard"
BODY_TYPE"PLUMBING"
HDL_TAP"TRUE";
"B \NAC \NWC"11;
"S \NAC"
BN"2"156;
%"TAP"
"1","(-2900,2300)","2","standard","I35";
;
CDS_LIB"standard"
BODY_TYPE"PLUMBING"
HDL_TAP"TRUE";
"B \NAC \NWC"11;
"S \NAC"
BN"3"157;
%"TAP"
"1","(-2900,2350)","2","standard","I36";
;
CDS_LIB"standard"
BODY_TYPE"PLUMBING"
HDL_TAP"TRUE";
"B \NAC \NWC"11;
"S \NAC"
BN"4"175;
%"TAP"
"1","(-2900,2400)","2","standard","I37";
;
CDS_LIB"standard"
BODY_TYPE"PLUMBING"
HDL_TAP"TRUE";
"B \NAC \NWC"11;
"S \NAC"
BN"5"158;
%"TAP"
"1","(-2900,2450)","2","standard","I38";
;
CDS_LIB"standard"
BODY_TYPE"PLUMBING"
HDL_TAP"TRUE";
"B \NAC \NWC"11;
"S \NAC"
BN"6"159;
%"TAP"
"1","(-2900,2500)","2","standard","I39";
;
CDS_LIB"standard"
BODY_TYPE"PLUMBING"
HDL_TAP"TRUE";
"B \NAC \NWC"11;
"S \NAC"
BN"7"176;
%"TAP"
"1","(-2900,3200)","2","standard","I40";
;
CDS_LIB"standard"
BODY_TYPE"PLUMBING"
HDL_TAP"TRUE";
"B \NAC \NWC"14;
"S \NAC"
BN"0"171;
%"TAP"
"1","(-2900,3250)","2","standard","I41";
;
CDS_LIB"standard"
BODY_TYPE"PLUMBING"
HDL_TAP"TRUE";
"B \NAC \NWC"14;
"S \NAC"
BN"1"169;
%"TAP"
"1","(-2900,3300)","2","standard","I42";
;
CDS_LIB"standard"
BODY_TYPE"PLUMBING"
HDL_TAP"TRUE";
"B \NAC \NWC"14;
"S \NAC"
BN"2"168;
%"TAP"
"1","(-2900,3350)","2","standard","I43";
;
CDS_LIB"standard"
BODY_TYPE"PLUMBING"
HDL_TAP"TRUE";
"B \NAC \NWC"14;
"S \NAC"
BN"3"166;
%"TAP"
"1","(-2900,3400)","2","standard","I44";
;
CDS_LIB"standard"
BODY_TYPE"PLUMBING"
HDL_TAP"TRUE";
"B \NAC \NWC"14;
"S \NAC"
BN"4"164;
%"TAP"
"1","(-2900,3500)","2","standard","I45";
;
CDS_LIB"standard"
BODY_TYPE"PLUMBING"
HDL_TAP"TRUE";
"B \NAC \NWC"14;
"S \NAC"
BN"6"160;
%"TAP"
"1","(-2900,3450)","2","standard","I46";
;
CDS_LIB"standard"
BODY_TYPE"PLUMBING"
HDL_TAP"TRUE";
"B \NAC \NWC"14;
"S \NAC"
BN"5"162;
%"TAP"
"1","(-2900,3600)","2","standard","I47";
;
CDS_LIB"standard"
BODY_TYPE"PLUMBING"
HDL_TAP"TRUE";
"B \NAC \NWC"13;
"S \NAC"
BN"0"172;
%"TAP"
"1","(-2900,3650)","2","standard","I48";
;
CDS_LIB"standard"
BODY_TYPE"PLUMBING"
HDL_TAP"TRUE";
"B \NAC \NWC"13;
"S \NAC"
BN"1"170;
%"TAP"
"1","(-2900,3750)","2","standard","I49";
;
CDS_LIB"standard"
BODY_TYPE"PLUMBING"
HDL_TAP"TRUE";
"B \NAC \NWC"13;
"S \NAC"
BN"3"167;
%"TAP"
"1","(-2900,3700)","2","standard","I50";
;
CDS_LIB"standard"
BODY_TYPE"PLUMBING"
HDL_TAP"TRUE";
"B \NAC \NWC"13;
"S \NAC"
BN"2"77;
%"SCONN288_ADR50017P087CC"
"1","(-2075,2175)","0","pure_quanta","I51";
;
PART_NUMBER"DFHST8FS460"
MATERIAL"IO"
VALUE"SCONN288_ADR50017-P087CC"
PART_TYPE"SMLF"
$LOCATION"J22"
NEEDS_NO_SIZE"TRUE"
CDS_LMAN_SYM_OUTLINE"-450,1875,450,-1875"
CDS_LIB"pure_quanta"
CDS_LOCATION"J22"
$SEC"1"
CDS_SEC"1";
"DQ31_A"
$PN"194"177;
"CB7_A"
$PN"205"176;
"CB4_A"
$PN"58"175;
"CB1_A"
$PN"53"174;
"CB7_B"
$PN"236"173;
"ALERT_N \B"
$PN"62"21;
"CA0_A"
$PN"66"172;
"CA0_B"
$PN"76"171;
"CA1_A"
$PN"211"170;
"CA1_B"
$PN"221"169;
"CA2_A"
$PN"68"77;
"CA2_B"
$PN"78"168;
"CA3_A"
$PN"213"167;
"CA3_B"
$PN"223"166;
"CA4_A"
$PN"70"165;
"CA4_B"
$PN"80"164;
"CA5_A"
$PN"215"163;
"CA5_B"
$PN"225"162;
"CA6_A"
$PN"72"161;
"CA6_B"
$PN"82"160;
"CB6_A"
$PN"203"159;
"CB5_A"
$PN"60"158;
"CB3_A"
$PN"198"157;
"CB2_A"
$PN"196"156;
"CB0_A"
$PN"51"155;
"CB6_B"
$PN"234"154;
"CB5_B"
$PN"91"153;
"CB4_B"
$PN"89"30;
"CB3_B"
$PN"243"152;
"CB2_B"
$PN"241"151;
"CB1_B"
$PN"98"150;
"CB0_B"
$PN"96"25;
"CK_C \B"
$PN"218"79;
"CK_T"
$PN"217"78;
"CS0_A_N"
$PN"64"33;
"CS0_B_N"
$PN"84"31;
"CS1_A_N"
$PN"209"149;
"CS1_B_N"
$PN"229"32;
"DQ30_A"
$PN"192"148;
"DQ29_A"
$PN"49"147;
"DQ28_A"
$PN"47"76;
"DQ27_A"
$PN"187"146;
"DQ26_A"
$PN"185"145;
"DQ25_A"
$PN"42"144;
"DQ24_A"
$PN"40"143;
"DQ23_A"
$PN"183"142;
"DQ22_A"
$PN"181"141;
"DQ21_A"
$PN"38"140;
"DQ20_A"
$PN"36"139;
"DQ19_A"
$PN"176"138;
"DQ18_A"
$PN"174"137;
"DQ17_A"
$PN"31"136;
"DQ16_A"
$PN"29"135;
"DQ15_A"
$PN"172"134;
"DQ14_A"
$PN"170"133;
"DQ13_A"
$PN"27"132;
"DQ12_A"
$PN"25"131;
"DQ11_A"
$PN"165"130;
"DQ10_A"
$PN"163"129;
"DQ9_A"
$PN"20"128;
"DQ8_A"
$PN"18"127;
"DQ7_A"
$PN"161"126;
"DQ6_A"
$PN"159"125;
"DQ5_A"
$PN"16"124;
"DQ4_A"
$PN"14"123;
"DQ3_A"
$PN"154"122;
"DQ2_A"
$PN"152"121;
"DQ1_A"
$PN"9"120;
"DQ0_A"
$PN"7"119;
"DQ31_B"
$PN"287"80;
"DQ30_B"
$PN"285"81;
"DQ29_B"
$PN"142"118;
"DQ28_B"
$PN"140"117;
"DQ27_B"
$PN"280"116;
"DQ26_B"
$PN"278"115;
"DQ25_B"
$PN"135"114;
"DQ24_B"
$PN"133"82;
"DQ23_B"
$PN"276"113;
"DQ22_B"
$PN"274"112;
"DQ21_B"
$PN"131"111;
"DQ20_B"
$PN"129"110;
"DQ19_B"
$PN"269"109;
"DQ18_B"
$PN"267"75;
"DQ17_B"
$PN"124"108;
"DQ16_B"
$PN"122"107;
"DQ15_B"
$PN"265"106;
"DQ14_B"
$PN"263"105;
"DQ13_B"
$PN"120"104;
"DQ12_B"
$PN"118"103;
"DQ11_B"
$PN"258"102;
"DQ10_B"
$PN"256"74;
"DQ9_B"
$PN"113"101;
"DQ8_B"
$PN"111"100;
"DQ7_B"
$PN"254"99;
"DQ6_B"
$PN"252"98;
"DQ5_B"
$PN"109"97;
"DQ4_B"
$PN"107"20;
"DQ3_B"
$PN"247"96;
"DQ2_B"
$PN"245"95;
"DQ1_B"
$PN"102"94;
"DQ0_B"
$PN"100"93;
"HSA"
$PN"148"23;
"HSCL"
$PN"4"26;
"HSDA"
$PN"5"22;
"LBD||RSP_A_N"
$PN"86"92;
"LBS||RSP_B_N"
$PN"87"91;
"PAR_A"
$PN"74"90;
"PAR_B"
$PN"227"89;
"PWR_GOOD||FAIL_N"
$PN"147"28;
"RESET_N \B"
$PN"207"24;
"RFU6"
$PN"232"29;
"RFU5"
$PN"231"88;
"RFU4"
$PN"220"87;
"RFU3"
$PN"150"86;
"RFU2"
$PN"149"85;
"RFU1"
$PN"144"84;
"RFU0"
$PN"2"83;
"VIN_MGMT"
$PN"3"4;
%"TAP"
"1","(-1250,700)","0","standard","I52";
;
CDS_LIB"standard"
BODY_TYPE"PLUMBING"
HDL_TAP"TRUE";
"B \NAC \NWC"15;
"S \NAC"
BN"0"93;
%"TAP"
"1","(-1250,750)","0","standard","I53";
;
CDS_LIB"standard"
BODY_TYPE"PLUMBING"
HDL_TAP"TRUE";
"B \NAC \NWC"15;
"S \NAC"
BN"1"94;
%"TAP"
"1","(-1250,850)","0","standard","I54";
;
CDS_LIB"standard"
BODY_TYPE"PLUMBING"
HDL_TAP"TRUE";
"B \NAC \NWC"15;
"S \NAC"
BN"3"96;
%"TAP"
"1","(-1250,800)","0","standard","I55";
;
CDS_LIB"standard"
BODY_TYPE"PLUMBING"
HDL_TAP"TRUE";
"B \NAC \NWC"15;
"S \NAC"
BN"2"95;
%"TAP"
"1","(-1250,900)","0","standard","I56";
;
CDS_LIB"standard"
BODY_TYPE"PLUMBING"
HDL_TAP"TRUE";
"B \NAC \NWC"15;
"S \NAC"
BN"4"20;
%"TAP"
"1","(-1250,950)","0","standard","I57";
;
CDS_LIB"standard"
BODY_TYPE"PLUMBING"
HDL_TAP"TRUE";
"B \NAC \NWC"15;
"S \NAC"
BN"5"97;
%"TAP"
"1","(-1250,1000)","0","standard","I58";
;
CDS_LIB"standard"
BODY_TYPE"PLUMBING"
HDL_TAP"TRUE";
"B \NAC \NWC"15;
"S \NAC"
BN"6"98;
%"TAP"
"1","(-1250,1100)","0","standard","I59";
;
CDS_LIB"standard"
BODY_TYPE"PLUMBING"
HDL_TAP"TRUE";
"B \NAC \NWC"15;
"S \NAC"
BN"8"100;
%"TAP"
"1","(-1250,1050)","0","standard","I60";
;
CDS_LIB"standard"
BODY_TYPE"PLUMBING"
HDL_TAP"TRUE";
"B \NAC \NWC"15;
"S \NAC"
BN"7"99;
%"TAP"
"1","(-1250,1150)","0","standard","I61";
;
CDS_LIB"standard"
BODY_TYPE"PLUMBING"
HDL_TAP"TRUE";
"B \NAC \NWC"15;
"S \NAC"
BN"9"101;
%"TAP"
"1","(-1250,1200)","0","standard","I62";
;
CDS_LIB"standard"
BODY_TYPE"PLUMBING"
HDL_TAP"TRUE";
"B \NAC \NWC"15;
"S \NAC"
BN"10"74;
%"TAP"
"1","(-1250,1250)","0","standard","I63";
;
CDS_LIB"standard"
BODY_TYPE"PLUMBING"
HDL_TAP"TRUE";
"B \NAC \NWC"15;
"S \NAC"
BN"11"102;
%"TAP"
"1","(-1250,1300)","0","standard","I64";
;
CDS_LIB"standard"
BODY_TYPE"PLUMBING"
HDL_TAP"TRUE";
"B \NAC \NWC"15;
"S \NAC"
BN"12"103;
%"TAP"
"1","(-1250,1350)","0","standard","I65";
;
CDS_LIB"standard"
BODY_TYPE"PLUMBING"
HDL_TAP"TRUE";
"B \NAC \NWC"15;
"S \NAC"
BN"13"104;
%"TAP"
"1","(-1250,1400)","0","standard","I66";
;
CDS_LIB"standard"
BODY_TYPE"PLUMBING"
HDL_TAP"TRUE";
"B \NAC \NWC"15;
"S \NAC"
BN"14"105;
%"TAP"
"1","(-1250,1450)","0","standard","I67";
;
CDS_LIB"standard"
BODY_TYPE"PLUMBING"
HDL_TAP"TRUE";
"B \NAC \NWC"15;
"S \NAC"
BN"15"106;
%"TAP"
"1","(-1250,1550)","0","standard","I68";
;
CDS_LIB"standard"
BODY_TYPE"PLUMBING"
HDL_TAP"TRUE";
"B \NAC \NWC"15;
"S \NAC"
BN"17"108;
%"TAP"
"1","(-1250,1500)","0","standard","I69";
;
CDS_LIB"standard"
BODY_TYPE"PLUMBING"
HDL_TAP"TRUE";
"B \NAC \NWC"15;
"S \NAC"
BN"16"107;
%"TAP"
"1","(-1250,1600)","0","standard","I70";
;
CDS_LIB"standard"
BODY_TYPE"PLUMBING"
HDL_TAP"TRUE";
"B \NAC \NWC"15;
"S \NAC"
BN"18"75;
%"TAP"
"1","(-1250,1650)","0","standard","I71";
;
CDS_LIB"standard"
BODY_TYPE"PLUMBING"
HDL_TAP"TRUE";
"B \NAC \NWC"15;
"S \NAC"
BN"19"109;
%"TAP"
"1","(-1250,1700)","0","standard","I72";
;
CDS_LIB"standard"
BODY_TYPE"PLUMBING"
HDL_TAP"TRUE";
"B \NAC \NWC"15;
"S \NAC"
BN"20"110;
%"TAP"
"1","(-1250,1750)","0","standard","I73";
;
CDS_LIB"standard"
BODY_TYPE"PLUMBING"
HDL_TAP"TRUE";
"B \NAC \NWC"15;
"S \NAC"
BN"21"111;
%"TAP"
"1","(-1250,1800)","0","standard","I74";
;
CDS_LIB"standard"
BODY_TYPE"PLUMBING"
HDL_TAP"TRUE";
"B \NAC \NWC"15;
"S \NAC"
BN"22"112;
%"TAP"
"1","(-1250,1850)","0","standard","I75";
;
CDS_LIB"standard"
BODY_TYPE"PLUMBING"
HDL_TAP"TRUE";
"B \NAC \NWC"15;
"S \NAC"
BN"23"113;
%"TAP"
"1","(-1250,1900)","0","standard","I76";
;
CDS_LIB"standard"
BODY_TYPE"PLUMBING"
HDL_TAP"TRUE";
"B \NAC \NWC"15;
"S \NAC"
BN"24"82;
%"TAP"
"1","(-1250,2000)","0","standard","I77";
;
CDS_LIB"standard"
BODY_TYPE"PLUMBING"
HDL_TAP"TRUE";
"B \NAC \NWC"15;
"S \NAC"
BN"26"115;
%"TAP"
"1","(-1250,1950)","0","standard","I78";
;
CDS_LIB"standard"
BODY_TYPE"PLUMBING"
HDL_TAP"TRUE";
"B \NAC \NWC"15;
"S \NAC"
BN"25"114;
%"TAP"
"1","(-1250,2050)","0","standard","I79";
;
CDS_LIB"standard"
BODY_TYPE"PLUMBING"
HDL_TAP"TRUE";
"B \NAC \NWC"15;
"S \NAC"
BN"27"116;
%"TAP"
"1","(-1250,2100)","0","standard","I80";
;
CDS_LIB"standard"
BODY_TYPE"PLUMBING"
HDL_TAP"TRUE";
"B \NAC \NWC"15;
"S \NAC"
BN"28"117;
%"TAP"
"1","(-1250,2150)","0","standard","I81";
;
CDS_LIB"standard"
BODY_TYPE"PLUMBING"
HDL_TAP"TRUE";
"B \NAC \NWC"15;
"S \NAC"
BN"29"118;
%"TAP"
"1","(-1250,2250)","0","standard","I82";
;
CDS_LIB"standard"
BODY_TYPE"PLUMBING"
HDL_TAP"TRUE";
"B \NAC \NWC"15;
"S \NAC"
BN"31"80;
%"TAP"
"1","(-1250,2200)","0","standard","I83";
;
CDS_LIB"standard"
BODY_TYPE"PLUMBING"
HDL_TAP"TRUE";
"B \NAC \NWC"15;
"S \NAC"
BN"30"81;
%"TAP"
"1","(-1250,2350)","0","standard","I84";
;
CDS_LIB"standard"
BODY_TYPE"PLUMBING"
HDL_TAP"TRUE";
"B \NAC \NWC"10;
"S \NAC"
BN"0"119;
%"TAP"
"1","(-1250,2450)","0","standard","I85";
;
CDS_LIB"standard"
BODY_TYPE"PLUMBING"
HDL_TAP"TRUE";
"B \NAC \NWC"10;
"S \NAC"
BN"2"121;
%"TAP"
"1","(-1250,2400)","0","standard","I86";
;
CDS_LIB"standard"
BODY_TYPE"PLUMBING"
HDL_TAP"TRUE";
"B \NAC \NWC"10;
"S \NAC"
BN"1"120;
%"TAP"
"1","(-1250,2500)","0","standard","I87";
;
CDS_LIB"standard"
BODY_TYPE"PLUMBING"
HDL_TAP"TRUE";
"B \NAC \NWC"10;
"S \NAC"
BN"3"122;
%"TAP"
"1","(-1250,2550)","0","standard","I88";
;
CDS_LIB"standard"
BODY_TYPE"PLUMBING"
HDL_TAP"TRUE";
"B \NAC \NWC"10;
"S \NAC"
BN"4"123;
%"TAP"
"1","(-1250,2600)","0","standard","I89";
;
CDS_LIB"standard"
BODY_TYPE"PLUMBING"
HDL_TAP"TRUE";
"B \NAC \NWC"10;
"S \NAC"
BN"5"124;
%"TAP"
"1","(-1250,2700)","0","standard","I90";
;
CDS_LIB"standard"
BODY_TYPE"PLUMBING"
HDL_TAP"TRUE";
"B \NAC \NWC"10;
"S \NAC"
BN"7"126;
%"TAP"
"1","(-1250,2650)","0","standard","I91";
;
CDS_LIB"standard"
BODY_TYPE"PLUMBING"
HDL_TAP"TRUE";
"B \NAC \NWC"10;
"S \NAC"
BN"6"125;
%"TAP"
"1","(-1250,2750)","0","standard","I92";
;
CDS_LIB"standard"
BODY_TYPE"PLUMBING"
HDL_TAP"TRUE";
"B \NAC \NWC"10;
"S \NAC"
BN"8"127;
%"TAP"
"1","(-1250,2800)","0","standard","I93";
;
CDS_LIB"standard"
BODY_TYPE"PLUMBING"
HDL_TAP"TRUE";
"B \NAC \NWC"10;
"S \NAC"
BN"9"128;
%"TAP"
"1","(-1250,2850)","0","standard","I94";
;
CDS_LIB"standard"
BODY_TYPE"PLUMBING"
HDL_TAP"TRUE";
"B \NAC \NWC"10;
"S \NAC"
BN"10"129;
%"TAP"
"1","(-1250,2900)","0","standard","I95";
;
CDS_LIB"standard"
BODY_TYPE"PLUMBING"
HDL_TAP"TRUE";
"B \NAC \NWC"10;
"S \NAC"
BN"11"130;
%"TAP"
"1","(-1250,2950)","0","standard","I96";
;
CDS_LIB"standard"
BODY_TYPE"PLUMBING"
HDL_TAP"TRUE";
"B \NAC \NWC"10;
"S \NAC"
BN"12"131;
%"TAP"
"1","(-1250,3000)","0","standard","I97";
;
CDS_LIB"standard"
BODY_TYPE"PLUMBING"
HDL_TAP"TRUE";
"B \NAC \NWC"10;
"S \NAC"
BN"13"132;
%"TAP"
"1","(-1250,3050)","0","standard","I98";
;
CDS_LIB"standard"
BODY_TYPE"PLUMBING"
HDL_TAP"TRUE";
"B \NAC \NWC"10;
"S \NAC"
BN"14"133;
%"TAP"
"1","(-1250,3150)","0","standard","I99";
;
CDS_LIB"standard"
BODY_TYPE"PLUMBING"
HDL_TAP"TRUE";
"B \NAC \NWC"10;
"S \NAC"
BN"16"135;
END.
